(kicad_pcb
	(version 20260206)
	(generator "pcbnew")
	(generator_version "10.0")
	(general
		(thickness 1.6)
		(legacy_teardrops no)
	)
	(paper "A4")
	(title_block
		(title "04192023_DAF0TMB3IC0_F0TG_MB_C_brd_V02_OCP.brd")
		(comment 1 "Grand Teton / footprints 6295-6302 of 8354")
	)
	(layers
		(0 "F.Cu" signal "TOP")
		(4 "In1.Cu" signal "GND")
		(6 "In2.Cu" signal "IN1")
		(8 "In3.Cu" signal "GND1")
		(10 "In4.Cu" signal "IN2")
		(12 "In5.Cu" signal "GND2")
		(14 "In6.Cu" signal "IN3")
		(16 "In7.Cu" signal "GND3")
		(18 "In8.Cu" signal "VCC")
		(20 "In9.Cu" signal "VCC1")
		(22 "In10.Cu" signal "GND4")
		(24 "In11.Cu" signal "IN4")
		(26 "In12.Cu" signal "GND5")
		(28 "In13.Cu" signal "IN5")
		(30 "In14.Cu" signal "GND6")
		(32 "In15.Cu" signal "IN6")
		(34 "In16.Cu" signal "GND7")
		(2 "B.Cu" signal "BOTTOM")
		(9 "F.Adhes" user "F.Adhesive")
		(11 "B.Adhes" user "B.Adhesive")
		(13 "F.Paste" user "Package Geometry/Pastemask Top")
		(15 "B.Paste" user "Package Geometry/Pastemask Bottom")
		(5 "F.SilkS" user "Ref Des/Silkscreen Top")
		(7 "B.SilkS" user "Ref Des/Silkscreen Bottom")
		(1 "F.Mask" user "Board Geometry/Soldermask Top")
		(3 "B.Mask" user "Board Geometry/Soldermask Bottom")
		(17 "Dwgs.User" user "User.Drawings")
		(19 "Cmts.User" user "User.Comments")
		(21 "Eco1.User" user "User.Eco1")
		(23 "Eco2.User" user "User.Eco2")
		(25 "Edge.Cuts" user "Board Geometry/Outline")
		(27 "Margin" user)
		(31 "F.CrtYd" user "Package Geometry/Place Bound Top")
		(29 "B.CrtYd" user "Package Geometry/Place Bound Bottom")
		(35 "F.Fab" user "Ref Des/Assembly Top")
		(33 "B.Fab" user "Ref Des/Assembly Bottom")
	)
	(footprint ""
		(layer "B.Cu")
		(at 173.101 -30.099 -90)
		(property "Reference" "R8012"
			(at 0 0 90)
			(layer "B.SilkS")
			(hide yes)
			(effects
				(font
					(size 1.27 1.27)
				)
				(justify mirror)
			)
		)
		(property "Value" ""
			(at 0 0 90)
			(layer "B.Fab")
			(effects
				(font
					(size 1.27 1.27)
				)
				(justify mirror)
			)
		)
		(duplicate_pad_numbers_are_jumpers no)
		(fp_line
			(start -0.7874 0.4064)
			(end 0.7874 0.4064)
			(stroke
				(width 0.1524)
				(type default)
			)
			(layer "B.SilkS")
		)
		(fp_line
			(start 0.7874 0.4064)
			(end 0.7874 -0.4064)
			(stroke
				(width 0.1524)
				(type default)
			)
			(layer "B.SilkS")
		)
		(fp_line
			(start -0.7874 -0.4064)
			(end -0.7874 0.4064)
			(stroke
				(width 0.1524)
				(type default)
			)
			(layer "B.SilkS")
		)
		(fp_line
			(start 0.7874 -0.4064)
			(end -0.7874 -0.4064)
			(stroke
				(width 0.1524)
				(type default)
			)
			(layer "B.SilkS")
		)
		(fp_line
			(start -0.67945 0.3048)
			(end -0.120396 0.3048)
			(stroke
				(width 0.1)
				(type default)
			)
			(layer "B.Fab")
		)
		(fp_line
			(start -0.120396 0.3048)
			(end -0.120396 0.2794)
			(stroke
				(width 0.1)
				(type default)
			)
			(layer "B.Fab")
		)
		(fp_line
			(start 0.12065 0.3048)
			(end 0.67945 0.3048)
			(stroke
				(width 0.1)
				(type default)
			)
			(layer "B.Fab")
		)
		(fp_line
			(start 0.67945 0.3048)
			(end 0.67945 -0.305054)
			(stroke
				(width 0.1)
				(type default)
			)
			(layer "B.Fab")
		)
		(fp_line
			(start -0.120396 0.2794)
			(end 0.12065 0.2794)
			(stroke
				(width 0.1)
				(type default)
			)
			(layer "B.Fab")
		)
		(fp_line
			(start 0.12065 0.2794)
			(end 0.12065 0.3048)
			(stroke
				(width 0.1)
				(type default)
			)
			(layer "B.Fab")
		)
		(fp_line
			(start -0.12065 -0.2794)
			(end -0.12065 -0.3048)
			(stroke
				(width 0.1)
				(type default)
			)
			(layer "B.Fab")
		)
		(fp_line
			(start 0.12065 -0.2794)
			(end -0.12065 -0.2794)
			(stroke
				(width 0.1)
				(type default)
			)
			(layer "B.Fab")
		)
		(fp_line
			(start -0.67945 -0.3048)
			(end -0.67945 0.3048)
			(stroke
				(width 0.1)
				(type default)
			)
			(layer "B.Fab")
		)
		(fp_line
			(start -0.12065 -0.3048)
			(end -0.67945 -0.3048)
			(stroke
				(width 0.1)
				(type default)
			)
			(layer "B.Fab")
		)
		(fp_line
			(start 0.12065 -0.305054)
			(end 0.12065 -0.2794)
			(stroke
				(width 0.1)
				(type default)
			)
			(layer "B.Fab")
		)
		(fp_line
			(start 0.67945 -0.305054)
			(end 0.12065 -0.305054)
			(stroke
				(width 0.1)
				(type default)
			)
			(layer "B.Fab")
		)
		(pad "1" smd circle
			(at 0.40005 0 90)
			(size 0 0)
			(layers "B.Cu" "B.Mask" "B.Paste")
			(net "HP_LVC3_SCM_HSC_PWRGD_R")
		)
		(pad "2" smd circle
			(at -0.40005 0 90)
			(size 0 0)
			(layers "B.Cu" "B.Mask" "B.Paste")
			(net "HP_LVC3_SCM_HSC_PWRGD")
		)
	)
	(footprint ""
		(layer "B.Cu")
		(at 366.36579 -392.1252 180)
		(property "Reference" "R1106"
			(at 0 0 0)
			(layer "B.SilkS")
			(hide yes)
			(effects
				(font
					(size 1.27 1.27)
				)
				(justify mirror)
			)
		)
		(property "Value" ""
			(at 0 0 0)
			(layer "B.Fab")
			(effects
				(font
					(size 1.27 1.27)
				)
				(justify mirror)
			)
		)
		(duplicate_pad_numbers_are_jumpers no)
		(fp_line
			(start 0.32512 0.175006)
			(end 0.32512 -0.175006)
			(stroke
				(width 0.1)
				(type default)
			)
			(layer "B.Fab")
		)
		(fp_line
			(start 0.32512 -0.175006)
			(end -0.32512 -0.175006)
			(stroke
				(width 0.1)
				(type default)
			)
			(layer "B.Fab")
		)
		(fp_line
			(start -0.32512 0.175006)
			(end 0.32512 0.175006)
			(stroke
				(width 0.1)
				(type default)
			)
			(layer "B.Fab")
		)
		(fp_line
			(start -0.32512 -0.175006)
			(end -0.32512 0.175006)
			(stroke
				(width 0.1)
				(type default)
			)
			(layer "B.Fab")
		)
		(pad "1" smd rect
			(at 0.2667 0)
			(size 0.3048 0.381)
			(layers "B.Cu" "B.Mask" "B.Paste")
			(net "RT_CPU0_P3_SCAN_MODE")
		)
		(pad "2" smd rect
			(at -0.2667 0 180)
			(size 0.3048 0.381)
			(layers "B.Cu" "B.Mask" "B.Paste")
			(net "GND")
		)
	)
	(footprint ""
		(layer "B.Cu")
		(at 230.6828 -334.01 180)
		(property "Reference" "R6761"
			(at 0 0 0)
			(layer "B.SilkS")
			(hide yes)
			(effects
				(font
					(size 1.27 1.27)
				)
				(justify mirror)
			)
		)
		(property "Value" ""
			(at 0 0 0)
			(layer "B.Fab")
			(effects
				(font
					(size 1.27 1.27)
				)
				(justify mirror)
			)
		)
		(duplicate_pad_numbers_are_jumpers no)
		(fp_line
			(start 0.32512 0.175006)
			(end 0.32512 -0.175006)
			(stroke
				(width 0.1)
				(type default)
			)
			(layer "B.Fab")
		)
		(fp_line
			(start 0.32512 -0.175006)
			(end -0.32512 -0.175006)
			(stroke
				(width 0.1)
				(type default)
			)
			(layer "B.Fab")
		)
		(fp_line
			(start -0.32512 0.175006)
			(end 0.32512 0.175006)
			(stroke
				(width 0.1)
				(type default)
			)
			(layer "B.Fab")
		)
		(fp_line
			(start -0.32512 -0.175006)
			(end -0.32512 0.175006)
			(stroke
				(width 0.1)
				(type default)
			)
			(layer "B.Fab")
		)
		(pad "1" smd rect
			(at 0.2667 0)
			(size 0.3048 0.381)
			(layers "B.Cu" "B.Mask" "B.Paste")
			(net "SMB_RT_CPU0_P2_SCL")
		)
		(pad "2" smd rect
			(at -0.2667 0 180)
			(size 0.3048 0.381)
			(layers "B.Cu" "B.Mask" "B.Paste")
			(net "SMB_RT_CPU0_P2_R_SCL")
		)
	)
	(footprint ""
		(layer "B.Cu")
		(at 184.785 -100.294948 90)
		(property "Reference" "R1186"
			(at 0 0 90)
			(layer "B.SilkS")
			(hide yes)
			(effects
				(font
					(size 1.27 1.27)
				)
				(justify mirror)
			)
		)
		(property "Value" ""
			(at 0 0 90)
			(layer "B.Fab")
			(effects
				(font
					(size 1.27 1.27)
				)
				(justify mirror)
			)
		)
		(duplicate_pad_numbers_are_jumpers no)
		(fp_line
			(start 0.7874 -0.4064)
			(end -0.7874 -0.4064)
			(stroke
				(width 0.1524)
				(type default)
			)
			(layer "B.SilkS")
		)
		(fp_line
			(start -0.7874 -0.4064)
			(end -0.7874 0.4064)
			(stroke
				(width 0.1524)
				(type default)
			)
			(layer "B.SilkS")
		)
		(fp_line
			(start 0.7874 0.4064)
			(end 0.7874 -0.4064)
			(stroke
				(width 0.1524)
				(type default)
			)
			(layer "B.SilkS")
		)
		(fp_line
			(start -0.7874 0.4064)
			(end 0.7874 0.4064)
			(stroke
				(width 0.1524)
				(type default)
			)
			(layer "B.SilkS")
		)
		(fp_line
			(start 0.67945 -0.305054)
			(end 0.12065 -0.305054)
			(stroke
				(width 0.1)
				(type default)
			)
			(layer "B.Fab")
		)
		(fp_line
			(start 0.12065 -0.305054)
			(end 0.12065 -0.2794)
			(stroke
				(width 0.1)
				(type default)
			)
			(layer "B.Fab")
		)
		(fp_line
			(start -0.12065 -0.3048)
			(end -0.67945 -0.3048)
			(stroke
				(width 0.1)
				(type default)
			)
			(layer "B.Fab")
		)
		(fp_line
			(start -0.67945 -0.3048)
			(end -0.67945 0.3048)
			(stroke
				(width 0.1)
				(type default)
			)
			(layer "B.Fab")
		)
		(fp_line
			(start 0.12065 -0.2794)
			(end -0.12065 -0.2794)
			(stroke
				(width 0.1)
				(type default)
			)
			(layer "B.Fab")
		)
		(fp_line
			(start -0.12065 -0.2794)
			(end -0.12065 -0.3048)
			(stroke
				(width 0.1)
				(type default)
			)
			(layer "B.Fab")
		)
		(fp_line
			(start 0.12065 0.2794)
			(end 0.12065 0.3048)
			(stroke
				(width 0.1)
				(type default)
			)
			(layer "B.Fab")
		)
		(fp_line
			(start -0.120396 0.2794)
			(end 0.12065 0.2794)
			(stroke
				(width 0.1)
				(type default)
			)
			(layer "B.Fab")
		)
		(fp_line
			(start 0.67945 0.3048)
			(end 0.67945 -0.305054)
			(stroke
				(width 0.1)
				(type default)
			)
			(layer "B.Fab")
		)
		(fp_line
			(start 0.12065 0.3048)
			(end 0.67945 0.3048)
			(stroke
				(width 0.1)
				(type default)
			)
			(layer "B.Fab")
		)
		(fp_line
			(start -0.120396 0.3048)
			(end -0.120396 0.2794)
			(stroke
				(width 0.1)
				(type default)
			)
			(layer "B.Fab")
		)
		(fp_line
			(start -0.67945 0.3048)
			(end -0.120396 0.3048)
			(stroke
				(width 0.1)
				(type default)
			)
			(layer "B.Fab")
		)
		(pad "1" smd circle
			(at 0.40005 0 270)
			(size 0 0)
			(layers "B.Cu" "B.Mask" "B.Paste")
			(net "PVDDCR_CPU1_P0_SMB_ALERT")
		)
		(pad "2" smd circle
			(at -0.40005 0 270)
			(size 0 0)
			(layers "B.Cu" "B.Mask" "B.Paste")
			(net "P3V3_AUX")
		)
	)
	(footprint ""
		(layer "B.Cu")
		(at 381.590042 -416.899344 90)
		(property "Reference" "C6604"
			(at 0 0 90)
			(layer "B.SilkS")
			(hide yes)
			(effects
				(font
					(size 1.27 1.27)
				)
				(justify mirror)
			)
		)
		(property "Value" ""
			(at 0 0 90)
			(layer "B.Fab")
			(effects
				(font
					(size 1.27 1.27)
				)
				(justify mirror)
			)
		)
		(duplicate_pad_numbers_are_jumpers no)
		(fp_line
			(start 0.299974 -0.150114)
			(end -0.299974 -0.150114)
			(stroke
				(width 0.1)
				(type default)
			)
			(layer "B.Fab")
		)
		(fp_line
			(start -0.299974 -0.150114)
			(end -0.299974 0.150114)
			(stroke
				(width 0.1)
				(type default)
			)
			(layer "B.Fab")
		)
		(fp_line
			(start 0.299974 0.150114)
			(end 0.299974 -0.150114)
			(stroke
				(width 0.1)
				(type default)
			)
			(layer "B.Fab")
		)
		(fp_line
			(start -0.299974 0.150114)
			(end 0.299974 0.150114)
			(stroke
				(width 0.1)
				(type default)
			)
			(layer "B.Fab")
		)
		(pad "1" smd rect
			(at 0.2667 0 270)
			(size 0.3048 0.381)
			(layers "B.Cu" "B.Mask" "B.Paste")
			(net "P5E_CPU0_P3_TX_BUF_C_DN<3>")
		)
		(pad "2" smd rect
			(at -0.2667 0 270)
			(size 0.3048 0.381)
			(layers "B.Cu" "B.Mask" "B.Paste")
			(net "P5E_CPU0_P3_TX_BUF_DN<3>")
		)
	)
	(footprint ""
		(layer "B.Cu")
		(at 79.175864 -11.26871 -90)
		(property "Reference" "R8413"
			(at 0 0 90)
			(layer "B.SilkS")
			(hide yes)
			(effects
				(font
					(size 1.27 1.27)
				)
				(justify mirror)
			)
		)
		(property "Value" ""
			(at 0 0 90)
			(layer "B.Fab")
			(effects
				(font
					(size 1.27 1.27)
				)
				(justify mirror)
			)
		)
		(duplicate_pad_numbers_are_jumpers no)
		(fp_line
			(start -0.7874 0.4064)
			(end 0.7874 0.4064)
			(stroke
				(width 0.1524)
				(type default)
			)
			(layer "B.SilkS")
		)
		(fp_line
			(start 0.7874 0.4064)
			(end 0.7874 -0.4064)
			(stroke
				(width 0.1524)
				(type default)
			)
			(layer "B.SilkS")
		)
		(fp_line
			(start -0.7874 -0.4064)
			(end -0.7874 0.4064)
			(stroke
				(width 0.1524)
				(type default)
			)
			(layer "B.SilkS")
		)
		(fp_line
			(start 0.7874 -0.4064)
			(end -0.7874 -0.4064)
			(stroke
				(width 0.1524)
				(type default)
			)
			(layer "B.SilkS")
		)
		(fp_line
			(start -0.67945 0.3048)
			(end -0.120396 0.3048)
			(stroke
				(width 0.1)
				(type default)
			)
			(layer "B.Fab")
		)
		(fp_line
			(start -0.120396 0.3048)
			(end -0.120396 0.2794)
			(stroke
				(width 0.1)
				(type default)
			)
			(layer "B.Fab")
		)
		(fp_line
			(start 0.12065 0.3048)
			(end 0.67945 0.3048)
			(stroke
				(width 0.1)
				(type default)
			)
			(layer "B.Fab")
		)
		(fp_line
			(start 0.67945 0.3048)
			(end 0.67945 -0.305054)
			(stroke
				(width 0.1)
				(type default)
			)
			(layer "B.Fab")
		)
		(fp_line
			(start -0.120396 0.2794)
			(end 0.12065 0.2794)
			(stroke
				(width 0.1)
				(type default)
			)
			(layer "B.Fab")
		)
		(fp_line
			(start 0.12065 0.2794)
			(end 0.12065 0.3048)
			(stroke
				(width 0.1)
				(type default)
			)
			(layer "B.Fab")
		)
		(fp_line
			(start -0.12065 -0.2794)
			(end -0.12065 -0.3048)
			(stroke
				(width 0.1)
				(type default)
			)
			(layer "B.Fab")
		)
		(fp_line
			(start 0.12065 -0.2794)
			(end -0.12065 -0.2794)
			(stroke
				(width 0.1)
				(type default)
			)
			(layer "B.Fab")
		)
		(fp_line
			(start -0.67945 -0.3048)
			(end -0.67945 0.3048)
			(stroke
				(width 0.1)
				(type default)
			)
			(layer "B.Fab")
		)
		(fp_line
			(start -0.12065 -0.3048)
			(end -0.67945 -0.3048)
			(stroke
				(width 0.1)
				(type default)
			)
			(layer "B.Fab")
		)
		(fp_line
			(start 0.12065 -0.305054)
			(end 0.12065 -0.2794)
			(stroke
				(width 0.1)
				(type default)
			)
			(layer "B.Fab")
		)
		(fp_line
			(start 0.67945 -0.305054)
			(end 0.12065 -0.305054)
			(stroke
				(width 0.1)
				(type default)
			)
			(layer "B.Fab")
		)
		(pad "1" smd circle
			(at 0.40005 0 90)
			(size 0 0)
			(layers "B.Cu" "B.Mask" "B.Paste")
			(net "GND")
		)
		(pad "2" smd circle
			(at -0.40005 0 90)
			(size 0 0)
			(layers "B.Cu" "B.Mask" "B.Paste")
			(net "FM_OCP_V3_2_PWR_GOOD")
		)
	)
	(footprint ""
		(layer "B.Cu")
		(at 237.363 -234.061 -90)
		(property "Reference" "R358"
			(at 0 0 90)
			(layer "B.SilkS")
			(hide yes)
			(effects
				(font
					(size 1.27 1.27)
				)
				(justify mirror)
			)
		)
		(property "Value" ""
			(at 0 0 90)
			(layer "B.Fab")
			(effects
				(font
					(size 1.27 1.27)
				)
				(justify mirror)
			)
		)
		(duplicate_pad_numbers_are_jumpers no)
		(fp_line
			(start -0.7874 0.4064)
			(end 0.7874 0.4064)
			(stroke
				(width 0.1524)
				(type default)
			)
			(layer "B.SilkS")
		)
		(fp_line
			(start 0.7874 0.4064)
			(end 0.7874 -0.4064)
			(stroke
				(width 0.1524)
				(type default)
			)
			(layer "B.SilkS")
		)
		(fp_line
			(start -0.7874 -0.4064)
			(end -0.7874 0.4064)
			(stroke
				(width 0.1524)
				(type default)
			)
			(layer "B.SilkS")
		)
		(fp_line
			(start 0.7874 -0.4064)
			(end -0.7874 -0.4064)
			(stroke
				(width 0.1524)
				(type default)
			)
			(layer "B.SilkS")
		)
		(fp_line
			(start -0.67945 0.3048)
			(end -0.120396 0.3048)
			(stroke
				(width 0.1)
				(type default)
			)
			(layer "B.Fab")
		)
		(fp_line
			(start -0.120396 0.3048)
			(end -0.120396 0.2794)
			(stroke
				(width 0.1)
				(type default)
			)
			(layer "B.Fab")
		)
		(fp_line
			(start 0.12065 0.3048)
			(end 0.67945 0.3048)
			(stroke
				(width 0.1)
				(type default)
			)
			(layer "B.Fab")
		)
		(fp_line
			(start 0.67945 0.3048)
			(end 0.67945 -0.305054)
			(stroke
				(width 0.1)
				(type default)
			)
			(layer "B.Fab")
		)
		(fp_line
			(start -0.120396 0.2794)
			(end 0.12065 0.2794)
			(stroke
				(width 0.1)
				(type default)
			)
			(layer "B.Fab")
		)
		(fp_line
			(start 0.12065 0.2794)
			(end 0.12065 0.3048)
			(stroke
				(width 0.1)
				(type default)
			)
			(layer "B.Fab")
		)
		(fp_line
			(start -0.12065 -0.2794)
			(end -0.12065 -0.3048)
			(stroke
				(width 0.1)
				(type default)
			)
			(layer "B.Fab")
		)
		(fp_line
			(start 0.12065 -0.2794)
			(end -0.12065 -0.2794)
			(stroke
				(width 0.1)
				(type default)
			)
			(layer "B.Fab")
		)
		(fp_line
			(start -0.67945 -0.3048)
			(end -0.67945 0.3048)
			(stroke
				(width 0.1)
				(type default)
			)
			(layer "B.Fab")
		)
		(fp_line
			(start -0.12065 -0.3048)
			(end -0.67945 -0.3048)
			(stroke
				(width 0.1)
				(type default)
			)
			(layer "B.Fab")
		)
		(fp_line
			(start 0.12065 -0.305054)
			(end 0.12065 -0.2794)
			(stroke
				(width 0.1)
				(type default)
			)
			(layer "B.Fab")
		)
		(fp_line
			(start 0.67945 -0.305054)
			(end 0.12065 -0.305054)
			(stroke
				(width 0.1)
				(type default)
			)
			(layer "B.Fab")
		)
		(pad "1" smd circle
			(at 0.40005 0 90)
			(size 0 0)
			(layers "B.Cu" "B.Mask" "B.Paste")
			(net "SMB_CPU0_CPU1_SEC_SCL_R2")
		)
		(pad "2" smd circle
			(at -0.40005 0 90)
			(size 0 0)
			(layers "B.Cu" "B.Mask" "B.Paste")
			(net "SMB_CPU1_SEC_R_SCL")
		)
	)
	(footprint ""
		(layer "B.Cu")
		(at 102.402386 -256.734564 180)
		(property "Reference" "C2474"
			(at 0 0 0)
			(layer "B.SilkS")
			(hide yes)
			(effects
				(font
					(size 1.27 1.27)
				)
				(justify mirror)
			)
		)
		(property "Value" ""
			(at 0 0 0)
			(layer "B.Fab")
			(effects
				(font
					(size 1.27 1.27)
				)
				(justify mirror)
			)
		)
		(duplicate_pad_numbers_are_jumpers no)
		(fp_line
			(start 0.7874 0.4064)
			(end 0.7874 -0.4064)
			(stroke
				(width 0.1524)
				(type default)
			)
			(layer "B.SilkS")
		)
		(fp_line
			(start 0.7874 -0.4064)
			(end -0.7874 -0.4064)
			(stroke
				(width 0.1524)
				(type default)
			)
			(layer "B.SilkS")
		)
		(fp_line
			(start -0.7874 0.4064)
			(end 0.7874 0.4064)
			(stroke
				(width 0.1524)
				(type default)
			)
			(layer "B.SilkS")
		)
		(fp_line
			(start -0.7874 -0.4064)
			(end -0.7874 0.4064)
			(stroke
				(width 0.1524)
				(type default)
			)
			(layer "B.SilkS")
		)
		(fp_line
			(start 0.67945 0.3048)
			(end 0.67945 -0.305054)
			(stroke
				(width 0.1)
				(type default)
			)
			(layer "B.Fab")
		)
		(fp_line
			(start 0.67945 -0.305054)
			(end 0.12065 -0.305054)
			(stroke
				(width 0.1)
				(type default)
			)
			(layer "B.Fab")
		)
		(fp_line
			(start 0.12065 0.3048)
			(end 0.67945 0.3048)
			(stroke
				(width 0.1)
				(type default)
			)
			(layer "B.Fab")
		)
		(fp_line
			(start 0.12065 0.2794)
			(end 0.12065 0.3048)
			(stroke
				(width 0.1)
				(type default)
			)
			(layer "B.Fab")
		)
		(fp_line
			(start 0.12065 -0.2794)
			(end -0.12065 -0.2794)
			(stroke
				(width 0.1)
				(type default)
			)
			(layer "B.Fab")
		)
		(fp_line
			(start 0.12065 -0.305054)
			(end 0.12065 -0.2794)
			(stroke
				(width 0.1)
				(type default)
			)
			(layer "B.Fab")
		)
		(fp_line
			(start -0.120396 0.3048)
			(end -0.120396 0.2794)
			(stroke
				(width 0.1)
				(type default)
			)
			(layer "B.Fab")
		)
		(fp_line
			(start -0.120396 0.2794)
			(end 0.12065 0.2794)
			(stroke
				(width 0.1)
				(type default)
			)
			(layer "B.Fab")
		)
		(fp_line
			(start -0.12065 -0.2794)
			(end -0.12065 -0.3048)
			(stroke
				(width 0.1)
				(type default)
			)
			(layer "B.Fab")
		)
		(fp_line
			(start -0.12065 -0.3048)
			(end -0.67945 -0.3048)
			(stroke
				(width 0.1)
				(type default)
			)
			(layer "B.Fab")
		)
		(fp_line
			(start -0.67945 0.3048)
			(end -0.120396 0.3048)
			(stroke
				(width 0.1)
				(type default)
			)
			(layer "B.Fab")
		)
		(fp_line
			(start -0.67945 -0.3048)
			(end -0.67945 0.3048)
			(stroke
				(width 0.1)
				(type default)
			)
			(layer "B.Fab")
		)
		(pad "1" smd circle
			(at 0.40005 0)
			(size 0 0)
			(layers "B.Cu" "B.Mask" "B.Paste")
			(net "PVDDCR_SOC_P1")
		)
		(pad "2" smd circle
			(at -0.40005 0)
			(size 0 0)
			(layers "B.Cu" "B.Mask" "B.Paste")
			(net "GND")
		)
	)
)
